# T6G (Grand Teton) — schematic netlist excerpt (pin names and nets, part order shuffled) for the footprints in the layout excerpt that follows; sources: Cadence DE-HDL packaged netlist, KiCad conversion of 04192023_DAF0TMB3IC0_F0TG_MB_C_brd_V02_OCP.brd

R9013  Q_RES  0 5% CHIP  pkg 0402LF  page 245 : A = PRSNT_CABLE_GPU_A2_ISO_N ; B = PRSNT_CABLE_GPU_A2_ISO_R1_N

U34  SN74LVC1G07DBVR  IC  pkg SMLF  page 142
  NC  = NC
  A  = OCP_V3_2_P3V3_R2_PWRGD
  GND  = GND
  Y  = OCP_V3_2_P3V3_PLD_PWRGD
  VCC  = P3V3_AUX

(kicad_pcb
	(version 20260206)
	(generator "pcbnew")
	(generator_version "10.0")
	(general
		(thickness 1.6)
		(legacy_teardrops no)
	)
	(paper "A4")
	(title_block
		(title "04192023_DAF0TMB3IC0_F0TG_MB_C_brd_V02_OCP.brd")
		(comment 1 "Grand Teton / footprints 3869-3870 of 8354")
	)
	(layers
		(0 "F.Cu" signal "TOP")
		(4 "In1.Cu" signal "GND")
		(6 "In2.Cu" signal "IN1")
		(8 "In3.Cu" signal "GND1")
		(10 "In4.Cu" signal "IN2")
		(12 "In5.Cu" signal "GND2")
		(14 "In6.Cu" signal "IN3")
		(16 "In7.Cu" signal "GND3")
		(18 "In8.Cu" signal "VCC")
		(20 "In9.Cu" signal "VCC1")
		(22 "In10.Cu" signal "GND4")
		(24 "In11.Cu" signal "IN4")
		(26 "In12.Cu" signal "GND5")
		(28 "In13.Cu" signal "IN5")
		(30 "In14.Cu" signal "GND6")
		(32 "In15.Cu" signal "IN6")
		(34 "In16.Cu" signal "GND7")
		(2 "B.Cu" signal "BOTTOM")
		(9 "F.Adhes" user "F.Adhesive")
		(11 "B.Adhes" user "B.Adhesive")
		(13 "F.Paste" user "Package Geometry/Pastemask Top")
		(15 "B.Paste" user "Package Geometry/Pastemask Bottom")
		(5 "F.SilkS" user "Ref Des/Silkscreen Top")
		(7 "B.SilkS" user "Ref Des/Silkscreen Bottom")
		(1 "F.Mask" user "Board Geometry/Soldermask Top")
		(3 "B.Mask" user "Board Geometry/Soldermask Bottom")
		(17 "Dwgs.User" user "User.Drawings")
		(19 "Cmts.User" user "User.Comments")
		(21 "Eco1.User" user "User.Eco1")
		(23 "Eco2.User" user "User.Eco2")
		(25 "Edge.Cuts" user "Board Geometry/Outline")
		(27 "Margin" user)
		(31 "F.CrtYd" user "Package Geometry/Place Bound Top")
		(29 "B.CrtYd" user "Package Geometry/Place Bound Bottom")
		(35 "F.Fab" user "Ref Des/Assembly Top")
		(33 "B.Fab" user "Ref Des/Assembly Bottom")
	)
	(footprint ""
		(layer "F.Cu")
		(at 189.366398 -426.375068 -90)
		(property "Reference" "R9013"
			(at 0 0 270)
			(layer "F.SilkS")
			(hide yes)
			(effects
				(font
					(size 1.27 1.27)
				)
			)
		)
		(property "Value" ""
			(at 0 0 270)
			(layer "F.Fab")
			(effects
				(font
					(size 1.27 1.27)
				)
			)
		)
		(duplicate_pad_numbers_are_jumpers no)
		(fp_line
			(start -0.7874 0.4064)
			(end -0.7874 -0.4064)
			(stroke
				(width 0.1524)
				(type default)
			)
			(layer "F.SilkS")
		)
		(fp_line
			(start 0.7874 0.4064)
			(end -0.7874 0.4064)
			(stroke
				(width 0.1524)
				(type default)
			)
			(layer "F.SilkS")
		)
		(fp_line
			(start -0.7874 -0.4064)
			(end 0.7874 -0.4064)
			(stroke
				(width 0.1524)
				(type default)
			)
			(layer "F.SilkS")
		)
		(fp_line
			(start 0.7874 -0.4064)
			(end 0.7874 0.4064)
			(stroke
				(width 0.1524)
				(type default)
			)
			(layer "F.SilkS")
		)
		(fp_line
			(start -0.67945 0.3048)
			(end -0.67945 -0.305054)
			(stroke
				(width 0.1)
				(type default)
			)
			(layer "F.Fab")
		)
		(fp_line
			(start -0.12065 0.3048)
			(end -0.67945 0.3048)
			(stroke
				(width 0.1)
				(type default)
			)
			(layer "F.Fab")
		)
		(fp_line
			(start 0.120396 0.3048)
			(end 0.120396 0.2794)
			(stroke
				(width 0.1)
				(type default)
			)
			(layer "F.Fab")
		)
		(fp_line
			(start 0.67945 0.3048)
			(end 0.120396 0.3048)
			(stroke
				(width 0.1)
				(type default)
			)
			(layer "F.Fab")
		)
		(fp_line
			(start -0.12065 0.2794)
			(end -0.12065 0.3048)
			(stroke
				(width 0.1)
				(type default)
			)
			(layer "F.Fab")
		)
		(fp_line
			(start 0.120396 0.2794)
			(end -0.12065 0.2794)
			(stroke
				(width 0.1)
				(type default)
			)
			(layer "F.Fab")
		)
		(fp_line
			(start -0.12065 -0.2794)
			(end 0.12065 -0.2794)
			(stroke
				(width 0.1)
				(type default)
			)
			(layer "F.Fab")
		)
		(fp_line
			(start 0.12065 -0.2794)
			(end 0.12065 -0.3048)
			(stroke
				(width 0.1)
				(type default)
			)
			(layer "F.Fab")
		)
		(fp_line
			(start 0.12065 -0.3048)
			(end 0.67945 -0.3048)
			(stroke
				(width 0.1)
				(type default)
			)
			(layer "F.Fab")
		)
		(fp_line
			(start 0.67945 -0.3048)
			(end 0.67945 0.3048)
			(stroke
				(width 0.1)
				(type default)
			)
			(layer "F.Fab")
		)
		(fp_line
			(start -0.67945 -0.305054)
			(end -0.12065 -0.305054)
			(stroke
				(width 0.1)
				(type default)
			)
			(layer "F.Fab")
		)
		(fp_line
			(start -0.12065 -0.305054)
			(end -0.12065 -0.2794)
			(stroke
				(width 0.1)
				(type default)
			)
			(layer "F.Fab")
		)
		(pad "1" smd circle
			(at -0.40005 0 270)
			(size 0 0)
			(layers "F.Cu" "F.Mask" "F.Paste")
			(net "PRSNT_CABLE_GPU_A2_ISO_N")
		)
		(pad "2" smd circle
			(at 0.40005 0 270)
			(size 0 0)
			(layers "F.Cu" "F.Mask" "F.Paste")
			(net "PRSNT_CABLE_GPU_A2_ISO_R1_N")
		)
	)
	(footprint ""
		(layer "F.Cu")
		(at 84.074 -69.596)
		(property "Reference" "U34"
			(at -2.032 -2.377948 0)
			(unlocked yes)
			(layer "F.SilkS")
			(effects
				(font
					(size 0.7874 0.5842)
					(thickness 0.1524)
				)
				(justify left)
			)
		)
		(property "Value" ""
			(at 0 0 0)
			(layer "F.Fab")
			(effects
				(font
					(size 1.27 1.27)
				)
			)
		)
		(duplicate_pad_numbers_are_jumpers no)
		(fp_line
			(start -2.0574 -1.651)
			(end -0.381 -1.651)
			(stroke
				(width 0.1524)
				(type default)
			)
			(layer "F.SilkS")
		)
		(fp_line
			(start -2.0574 1.651)
			(end -2.0574 -1.651)
			(stroke
				(width 0.1524)
				(type default)
			)
			(layer "F.SilkS")
		)
		(fp_line
			(start -0.381 -1.651)
			(end 0 -1.016)
			(stroke
				(width 0.1524)
				(type default)
			)
			(layer "F.SilkS")
		)
		(fp_line
			(start 0 -1.016)
			(end 0.381 -1.651)
			(stroke
				(width 0.1524)
				(type default)
			)
			(layer "F.SilkS")
		)
		(fp_line
			(start 0.381 -1.651)
			(end 2.0574 -1.651)
			(stroke
				(width 0.1524)
				(type default)
			)
			(layer "F.SilkS")
		)
		(fp_line
			(start 2.0574 -1.651)
			(end 2.0574 1.651)
			(stroke
				(width 0.1524)
				(type default)
			)
			(layer "F.SilkS")
		)
		(fp_line
			(start 2.0574 1.651)
			(end -2.0574 1.651)
			(stroke
				(width 0.1524)
				(type default)
			)
			(layer "F.SilkS")
		)
		(fp_poly
			(pts
				(xy -2.71272 -0.719328) (xy -2.71272 -1.344168) (xy -2.159 -1.016)
			)
			(stroke
				(width 0)
				(type default)
			)
			(fill yes)
			(layer "F.SilkS")
		)
		(fp_line
			(start -1.599946 -1.199896)
			(end -0.899922 -1.199896)
			(stroke
				(width 0.1)
				(type default)
			)
			(layer "F.Fab")
		)
		(fp_line
			(start -1.599946 1.199896)
			(end -1.599946 -1.199896)
			(stroke
				(width 0.1)
				(type default)
			)
			(layer "F.Fab")
		)
		(fp_line
			(start -0.899922 -1.549908)
			(end 0.899922 -1.549908)
			(stroke
				(width 0.1)
				(type default)
			)
			(layer "F.Fab")
		)
		(fp_line
			(start -0.899922 -1.199896)
			(end -0.899922 -1.549908)
			(stroke
				(width 0.1)
				(type default)
			)
			(layer "F.Fab")
		)
		(fp_line
			(start -0.899922 1.199896)
			(end -1.599946 1.199896)
			(stroke
				(width 0.1)
				(type default)
			)
			(layer "F.Fab")
		)
		(fp_line
			(start -0.899922 1.549908)
			(end -0.899922 1.199896)
			(stroke
				(width 0.1)
				(type default)
			)
			(layer "F.Fab")
		)
		(fp_line
			(start 0.899922 -1.549908)
			(end 0.899922 -1.199896)
			(stroke
				(width 0.1)
				(type default)
			)
			(layer "F.Fab")
		)
		(fp_line
			(start 0.899922 -1.199896)
			(end 1.599946 -1.199896)
			(stroke
				(width 0.1)
				(type default)
			)
			(layer "F.Fab")
		)
		(fp_line
			(start 0.899922 1.199896)
			(end 0.899922 1.549908)
			(stroke
				(width 0.1)
				(type default)
			)
			(layer "F.Fab")
		)
		(fp_line
			(start 0.899922 1.549908)
			(end -0.899922 1.549908)
			(stroke
				(width 0.1)
				(type default)
			)
			(layer "F.Fab")
		)
		(fp_line
			(start 1.599946 -1.199896)
			(end 1.599946 1.199896)
			(stroke
				(width 0.1)
				(type default)
			)
			(layer "F.Fab")
		)
		(fp_line
			(start 1.599946 1.199896)
			(end 0.899922 1.199896)
			(stroke
				(width 0.1)
				(type default)
			)
			(layer "F.Fab")
		)
		(fp_poly
			(pts
				(xy -2.71272 -0.719328) (xy -2.71272 -1.344168) (xy -2.159 -1.016)
			)
			(stroke
				(width 0)
				(type default)
			)
			(fill yes)
			(layer "F.Fab")
		)
		(pad "1" smd rect
			(at -1.225042 -0.94996 270)
			(size 0.5588 1.3462)
			(layers "F.Cu" "F.Mask" "F.Paste")
			(net "Net_10852")
		)
		(pad "2" smd rect
			(at -1.225042 0 270)
			(size 0.5588 1.3462)
			(layers "F.Cu" "F.Mask" "F.Paste")
			(net "OCP_V3_2_P3V3_R2_PWRGD")
		)
		(pad "3" smd rect
			(at -1.225042 0.94996 270)
			(size 0.5588 1.3462)
			(layers "F.Cu" "F.Mask" "F.Paste")
			(net "GND")
		)
		(pad "4" smd rect
			(at 1.225042 0.94996 270)
			(size 0.5588 1.3462)
			(layers "F.Cu" "F.Mask" "F.Paste")
			(net "OCP_V3_2_P3V3_PLD_PWRGD")
		)
		(pad "5" smd rect
			(at 1.225042 -0.94996 270)
			(size 0.5588 1.3462)
			(layers "F.Cu" "F.Mask" "F.Paste")
			(net "P3V3_AUX")
		)
	)
)
